(kicad_pcb
	(version 20260206)
	(generator "pcbnew")
	(generator_version "10.0")
	(general
		(thickness 1.6)
		(legacy_teardrops no)
	)
	(paper "A4")
	(title_block
		(title "03242023_DA0F0TMBIJ0_F0T_Motherboard_J_brd_V01_OCP.brd")
		(comment 1 "Grand Teton / footprints 4636-4642 of 6105")
	)
	(layers
		(0 "F.Cu" signal "TOP")
		(4 "In1.Cu" signal "GND")
		(6 "In2.Cu" signal "IN1")
		(8 "In3.Cu" signal "GND1")
		(10 "In4.Cu" signal "IN2")
		(12 "In5.Cu" signal "GND2")
		(14 "In6.Cu" signal "IN3")
		(16 "In7.Cu" signal "GND3")
		(18 "In8.Cu" signal "VCC")
		(20 "In9.Cu" signal "VCC1")
		(22 "In10.Cu" signal "GND4")
		(24 "In11.Cu" signal "IN4")
		(26 "In12.Cu" signal "GND5")
		(28 "In13.Cu" signal "IN5")
		(30 "In14.Cu" signal "GND6")
		(32 "In15.Cu" signal "IN6")
		(34 "In16.Cu" signal "GND7")
		(2 "B.Cu" signal "BOTTOM")
		(9 "F.Adhes" user "F.Adhesive")
		(11 "B.Adhes" user "B.Adhesive")
		(13 "F.Paste" user "Package Geometry/Pastemask Top")
		(15 "B.Paste" user "Package Geometry/Pastemask Bottom")
		(5 "F.SilkS" user "Ref Des/Silkscreen Top")
		(7 "B.SilkS" user "Ref Des/Silkscreen Bottom")
		(1 "F.Mask" user "Board Geometry/Soldermask Top")
		(3 "B.Mask" user "Board Geometry/Soldermask Bottom")
		(17 "Dwgs.User" user "User.Drawings")
		(19 "Cmts.User" user "User.Comments")
		(21 "Eco1.User" user "User.Eco1")
		(23 "Eco2.User" user "User.Eco2")
		(25 "Edge.Cuts" user "Board Geometry/Outline")
		(27 "Margin" user)
		(31 "F.CrtYd" user "Package Geometry/Place Bound Top")
		(29 "B.CrtYd" user "Package Geometry/Place Bound Bottom")
		(35 "F.Fab" user "Ref Des/Assembly Top")
		(33 "B.Fab" user "Ref Des/Assembly Bottom")
	)
	(footprint ""
		(layer "B.Cu")
		(at 450.43725 -44.171362)
		(property "Reference" "R425"
			(at 0 0 0)
			(layer "B.SilkS")
			(hide yes)
			(effects
				(font
					(size 1.27 1.27)
				)
				(justify mirror)
			)
		)
		(property "Value" ""
			(at 0 0 0)
			(layer "B.Fab")
			(effects
				(font
					(size 1.27 1.27)
				)
				(justify mirror)
			)
		)
		(duplicate_pad_numbers_are_jumpers no)
		(fp_line
			(start -0.7874 -0.4064)
			(end -0.7874 0.4064)
			(stroke
				(width 0.1524)
				(type default)
			)
			(layer "B.SilkS")
		)
		(fp_line
			(start -0.7874 0.4064)
			(end 0.7874 0.4064)
			(stroke
				(width 0.1524)
				(type default)
			)
			(layer "B.SilkS")
		)
		(fp_line
			(start 0.7874 -0.4064)
			(end -0.7874 -0.4064)
			(stroke
				(width 0.1524)
				(type default)
			)
			(layer "B.SilkS")
		)
		(fp_line
			(start 0.7874 0.4064)
			(end 0.7874 -0.4064)
			(stroke
				(width 0.1524)
				(type default)
			)
			(layer "B.SilkS")
		)
		(fp_line
			(start -0.67945 -0.3048)
			(end -0.67945 0.3048)
			(stroke
				(width 0.1)
				(type default)
			)
			(layer "B.Fab")
		)
		(fp_line
			(start -0.67945 0.3048)
			(end -0.120396 0.3048)
			(stroke
				(width 0.1)
				(type default)
			)
			(layer "B.Fab")
		)
		(fp_line
			(start -0.12065 -0.3048)
			(end -0.67945 -0.3048)
			(stroke
				(width 0.1)
				(type default)
			)
			(layer "B.Fab")
		)
		(fp_line
			(start -0.12065 -0.2794)
			(end -0.12065 -0.3048)
			(stroke
				(width 0.1)
				(type default)
			)
			(layer "B.Fab")
		)
		(fp_line
			(start -0.120396 0.2794)
			(end 0.12065 0.2794)
			(stroke
				(width 0.1)
				(type default)
			)
			(layer "B.Fab")
		)
		(fp_line
			(start -0.120396 0.3048)
			(end -0.120396 0.2794)
			(stroke
				(width 0.1)
				(type default)
			)
			(layer "B.Fab")
		)
		(fp_line
			(start 0.12065 -0.305054)
			(end 0.12065 -0.2794)
			(stroke
				(width 0.1)
				(type default)
			)
			(layer "B.Fab")
		)
		(fp_line
			(start 0.12065 -0.2794)
			(end -0.12065 -0.2794)
			(stroke
				(width 0.1)
				(type default)
			)
			(layer "B.Fab")
		)
		(fp_line
			(start 0.12065 0.2794)
			(end 0.12065 0.3048)
			(stroke
				(width 0.1)
				(type default)
			)
			(layer "B.Fab")
		)
		(fp_line
			(start 0.12065 0.3048)
			(end 0.67945 0.3048)
			(stroke
				(width 0.1)
				(type default)
			)
			(layer "B.Fab")
		)
		(fp_line
			(start 0.67945 -0.305054)
			(end 0.12065 -0.305054)
			(stroke
				(width 0.1)
				(type default)
			)
			(layer "B.Fab")
		)
		(fp_line
			(start 0.67945 0.3048)
			(end 0.67945 -0.305054)
			(stroke
				(width 0.1)
				(type default)
			)
			(layer "B.Fab")
		)
		(pad "1" smd circle
			(at 0.40005 0 180)
			(size 0 0)
			(layers "B.Cu" "B.Mask" "B.Paste")
			(net "SMB_OCP_SFF_3V3AUX_BUF_R_SDA")
		)
		(pad "2" smd circle
			(at -0.40005 0 180)
			(size 0 0)
			(layers "B.Cu" "B.Mask" "B.Paste")
			(net "SMB_OCP_SFF_3V3AUX_BUF_SDA")
		)
	)
	(footprint ""
		(layer "B.Cu")
		(at 246.8499 -96.761808)
		(property "Reference" "R3340"
			(at 0 0 0)
			(layer "B.SilkS")
			(hide yes)
			(effects
				(font
					(size 1.27 1.27)
				)
				(justify mirror)
			)
		)
		(property "Value" ""
			(at 0 0 0)
			(layer "B.Fab")
			(effects
				(font
					(size 1.27 1.27)
				)
				(justify mirror)
			)
		)
		(duplicate_pad_numbers_are_jumpers no)
		(fp_line
			(start -0.7874 -0.4064)
			(end -0.7874 0.4064)
			(stroke
				(width 0.1524)
				(type default)
			)
			(layer "B.SilkS")
		)
		(fp_line
			(start -0.7874 0.4064)
			(end 0.7874 0.4064)
			(stroke
				(width 0.1524)
				(type default)
			)
			(layer "B.SilkS")
		)
		(fp_line
			(start 0.7874 -0.4064)
			(end -0.7874 -0.4064)
			(stroke
				(width 0.1524)
				(type default)
			)
			(layer "B.SilkS")
		)
		(fp_line
			(start 0.7874 0.4064)
			(end 0.7874 -0.4064)
			(stroke
				(width 0.1524)
				(type default)
			)
			(layer "B.SilkS")
		)
		(fp_line
			(start -0.67945 -0.3048)
			(end -0.67945 0.3048)
			(stroke
				(width 0.1)
				(type default)
			)
			(layer "B.Fab")
		)
		(fp_line
			(start -0.67945 0.3048)
			(end -0.120396 0.3048)
			(stroke
				(width 0.1)
				(type default)
			)
			(layer "B.Fab")
		)
		(fp_line
			(start -0.12065 -0.3048)
			(end -0.67945 -0.3048)
			(stroke
				(width 0.1)
				(type default)
			)
			(layer "B.Fab")
		)
		(fp_line
			(start -0.12065 -0.2794)
			(end -0.12065 -0.3048)
			(stroke
				(width 0.1)
				(type default)
			)
			(layer "B.Fab")
		)
		(fp_line
			(start -0.120396 0.2794)
			(end 0.12065 0.2794)
			(stroke
				(width 0.1)
				(type default)
			)
			(layer "B.Fab")
		)
		(fp_line
			(start -0.120396 0.3048)
			(end -0.120396 0.2794)
			(stroke
				(width 0.1)
				(type default)
			)
			(layer "B.Fab")
		)
		(fp_line
			(start 0.12065 -0.305054)
			(end 0.12065 -0.2794)
			(stroke
				(width 0.1)
				(type default)
			)
			(layer "B.Fab")
		)
		(fp_line
			(start 0.12065 -0.2794)
			(end -0.12065 -0.2794)
			(stroke
				(width 0.1)
				(type default)
			)
			(layer "B.Fab")
		)
		(fp_line
			(start 0.12065 0.2794)
			(end 0.12065 0.3048)
			(stroke
				(width 0.1)
				(type default)
			)
			(layer "B.Fab")
		)
		(fp_line
			(start 0.12065 0.3048)
			(end 0.67945 0.3048)
			(stroke
				(width 0.1)
				(type default)
			)
			(layer "B.Fab")
		)
		(fp_line
			(start 0.67945 -0.305054)
			(end 0.12065 -0.305054)
			(stroke
				(width 0.1)
				(type default)
			)
			(layer "B.Fab")
		)
		(fp_line
			(start 0.67945 0.3048)
			(end 0.67945 -0.305054)
			(stroke
				(width 0.1)
				(type default)
			)
			(layer "B.Fab")
		)
		(pad "1" smd circle
			(at 0.40005 0 180)
			(size 0 0)
			(layers "B.Cu" "B.Mask" "B.Paste")
			(net "SMB_HOST_CLK_3V3AUX_SCL")
		)
		(pad "2" smd circle
			(at -0.40005 0 180)
			(size 0 0)
			(layers "B.Cu" "B.Mask" "B.Paste")
			(net "SMB_HOST_CLK_GEN2_3V3AUX_SCL")
		)
	)
	(footprint ""
		(layer "B.Cu")
		(at 116.40312 -252.17628 -90)
		(property "Reference" "C338"
			(at 0 0 90)
			(layer "B.SilkS")
			(hide yes)
			(effects
				(font
					(size 1.27 1.27)
				)
				(justify mirror)
			)
		)
		(property "Value" ""
			(at 0 0 90)
			(layer "B.Fab")
			(effects
				(font
					(size 1.27 1.27)
				)
				(justify mirror)
			)
		)
		(duplicate_pad_numbers_are_jumpers no)
		(fp_line
			(start -1.524 0.762)
			(end 1.524 0.762)
			(stroke
				(width 0.1524)
				(type default)
			)
			(layer "B.SilkS")
		)
		(fp_line
			(start 1.524 0.762)
			(end 1.524 -0.762)
			(stroke
				(width 0.1524)
				(type default)
			)
			(layer "B.SilkS")
		)
		(fp_line
			(start -1.524 -0.762)
			(end -1.524 0.762)
			(stroke
				(width 0.1524)
				(type default)
			)
			(layer "B.SilkS")
		)
		(fp_line
			(start 1.524 -0.762)
			(end -1.524 -0.762)
			(stroke
				(width 0.1524)
				(type default)
			)
			(layer "B.SilkS")
		)
		(fp_line
			(start -1.1049 0.724916)
			(end -1.1049 -0.724916)
			(stroke
				(width 0.1)
				(type default)
			)
			(layer "B.Fab")
		)
		(fp_line
			(start 1.1049 0.724916)
			(end -1.1049 0.724916)
			(stroke
				(width 0.1)
				(type default)
			)
			(layer "B.Fab")
		)
		(fp_line
			(start -1.1049 -0.724916)
			(end 1.1049 -0.724916)
			(stroke
				(width 0.1)
				(type default)
			)
			(layer "B.Fab")
		)
		(fp_line
			(start 1.1049 -0.724916)
			(end 1.1049 0.724916)
			(stroke
				(width 0.1)
				(type default)
			)
			(layer "B.Fab")
		)
		(pad "1" smd rect
			(at 0.889 0 270)
			(size 1.016 1.27)
			(layers "B.Cu" "B.Mask" "B.Paste")
			(net "PVCCIN_CPU1")
		)
		(pad "2" smd rect
			(at -0.889 0 270)
			(size 1.016 1.27)
			(layers "B.Cu" "B.Mask" "B.Paste")
			(net "GND")
		)
	)
	(footprint ""
		(layer "B.Cu")
		(at 63.616078 -192.93459 90)
		(property "Reference" "R135"
			(at 0 0 90)
			(layer "B.SilkS")
			(hide yes)
			(effects
				(font
					(size 1.27 1.27)
				)
				(justify mirror)
			)
		)
		(property "Value" ""
			(at 0 0 90)
			(layer "B.Fab")
			(effects
				(font
					(size 1.27 1.27)
				)
				(justify mirror)
			)
		)
		(duplicate_pad_numbers_are_jumpers no)
		(fp_line
			(start 0.7874 -0.4064)
			(end -0.7874 -0.4064)
			(stroke
				(width 0.1524)
				(type default)
			)
			(layer "B.SilkS")
		)
		(fp_line
			(start -0.7874 -0.4064)
			(end -0.7874 0.4064)
			(stroke
				(width 0.1524)
				(type default)
			)
			(layer "B.SilkS")
		)
		(fp_line
			(start 0.7874 0.4064)
			(end 0.7874 -0.4064)
			(stroke
				(width 0.1524)
				(type default)
			)
			(layer "B.SilkS")
		)
		(fp_line
			(start -0.7874 0.4064)
			(end 0.7874 0.4064)
			(stroke
				(width 0.1524)
				(type default)
			)
			(layer "B.SilkS")
		)
		(fp_line
			(start 0.67945 -0.305054)
			(end 0.12065 -0.305054)
			(stroke
				(width 0.1)
				(type default)
			)
			(layer "B.Fab")
		)
		(fp_line
			(start 0.12065 -0.305054)
			(end 0.12065 -0.2794)
			(stroke
				(width 0.1)
				(type default)
			)
			(layer "B.Fab")
		)
		(fp_line
			(start -0.12065 -0.3048)
			(end -0.67945 -0.3048)
			(stroke
				(width 0.1)
				(type default)
			)
			(layer "B.Fab")
		)
		(fp_line
			(start -0.67945 -0.3048)
			(end -0.67945 0.3048)
			(stroke
				(width 0.1)
				(type default)
			)
			(layer "B.Fab")
		)
		(fp_line
			(start 0.12065 -0.2794)
			(end -0.12065 -0.2794)
			(stroke
				(width 0.1)
				(type default)
			)
			(layer "B.Fab")
		)
		(fp_line
			(start -0.12065 -0.2794)
			(end -0.12065 -0.3048)
			(stroke
				(width 0.1)
				(type default)
			)
			(layer "B.Fab")
		)
		(fp_line
			(start 0.12065 0.2794)
			(end 0.12065 0.3048)
			(stroke
				(width 0.1)
				(type default)
			)
			(layer "B.Fab")
		)
		(fp_line
			(start -0.120396 0.2794)
			(end 0.12065 0.2794)
			(stroke
				(width 0.1)
				(type default)
			)
			(layer "B.Fab")
		)
		(fp_line
			(start 0.67945 0.3048)
			(end 0.67945 -0.305054)
			(stroke
				(width 0.1)
				(type default)
			)
			(layer "B.Fab")
		)
		(fp_line
			(start 0.12065 0.3048)
			(end 0.67945 0.3048)
			(stroke
				(width 0.1)
				(type default)
			)
			(layer "B.Fab")
		)
		(fp_line
			(start -0.120396 0.3048)
			(end -0.120396 0.2794)
			(stroke
				(width 0.1)
				(type default)
			)
			(layer "B.Fab")
		)
		(fp_line
			(start -0.67945 0.3048)
			(end -0.120396 0.3048)
			(stroke
				(width 0.1)
				(type default)
			)
			(layer "B.Fab")
		)
		(pad "1" smd circle
			(at 0.40005 0 270)
			(size 0 0)
			(layers "B.Cu" "B.Mask" "B.Paste")
			(net "PWRGD_DRAMPWRGD_CPU1_AB_LVC1_R2")
		)
		(pad "2" smd circle
			(at -0.40005 0 270)
			(size 0 0)
			(layers "B.Cu" "B.Mask" "B.Paste")
			(net "PVCCD_HV_CPU1")
		)
	)
	(footprint ""
		(layer "B.Cu")
		(at 54.880002 -159.734758 180)
		(property "Reference" "PC448_P1_1"
			(at 0 0 0)
			(layer "B.SilkS")
			(hide yes)
			(effects
				(font
					(size 1.27 1.27)
				)
				(justify mirror)
			)
		)
		(property "Value" ""
			(at 0 0 0)
			(layer "B.Fab")
			(effects
				(font
					(size 1.27 1.27)
				)
				(justify mirror)
			)
		)
		(duplicate_pad_numbers_are_jumpers no)
		(fp_line
			(start 1.524 0.762)
			(end 1.524 -0.762)
			(stroke
				(width 0.1524)
				(type default)
			)
			(layer "B.SilkS")
		)
		(fp_line
			(start 1.524 -0.762)
			(end -1.524 -0.762)
			(stroke
				(width 0.1524)
				(type default)
			)
			(layer "B.SilkS")
		)
		(fp_line
			(start -1.524 0.762)
			(end 1.524 0.762)
			(stroke
				(width 0.1524)
				(type default)
			)
			(layer "B.SilkS")
		)
		(fp_line
			(start -1.524 -0.762)
			(end -1.524 0.762)
			(stroke
				(width 0.1524)
				(type default)
			)
			(layer "B.SilkS")
		)
		(fp_line
			(start 1.1049 0.724916)
			(end -1.1049 0.724916)
			(stroke
				(width 0.1)
				(type default)
			)
			(layer "B.Fab")
		)
		(fp_line
			(start 1.1049 -0.724916)
			(end 1.1049 0.724916)
			(stroke
				(width 0.1)
				(type default)
			)
			(layer "B.Fab")
		)
		(fp_line
			(start -1.1049 0.724916)
			(end -1.1049 -0.724916)
			(stroke
				(width 0.1)
				(type default)
			)
			(layer "B.Fab")
		)
		(fp_line
			(start -1.1049 -0.724916)
			(end 1.1049 -0.724916)
			(stroke
				(width 0.1)
				(type default)
			)
			(layer "B.Fab")
		)
		(pad "1" smd rect
			(at 0.889 0 180)
			(size 1.016 1.27)
			(layers "B.Cu" "B.Mask" "B.Paste")
			(net "SW_P12V_PVCCINFAON_CPU1_FLT")
		)
		(pad "2" smd rect
			(at -0.889 0 180)
			(size 1.016 1.27)
			(layers "B.Cu" "B.Mask" "B.Paste")
			(net "GND")
		)
	)
	(footprint ""
		(layer "B.Cu")
		(at 312.592974 -319.069212 90)
		(property "Reference" "R2727"
			(at 0 0 90)
			(layer "B.SilkS")
			(hide yes)
			(effects
				(font
					(size 1.27 1.27)
				)
				(justify mirror)
			)
		)
		(property "Value" ""
			(at 0 0 90)
			(layer "B.Fab")
			(effects
				(font
					(size 1.27 1.27)
				)
				(justify mirror)
			)
		)
		(duplicate_pad_numbers_are_jumpers no)
		(fp_line
			(start 0.7874 -0.4064)
			(end -0.7874 -0.4064)
			(stroke
				(width 0.1524)
				(type default)
			)
			(layer "B.SilkS")
		)
		(fp_line
			(start -0.7874 -0.4064)
			(end -0.7874 0.4064)
			(stroke
				(width 0.1524)
				(type default)
			)
			(layer "B.SilkS")
		)
		(fp_line
			(start 0.7874 0.4064)
			(end 0.7874 -0.4064)
			(stroke
				(width 0.1524)
				(type default)
			)
			(layer "B.SilkS")
		)
		(fp_line
			(start -0.7874 0.4064)
			(end 0.7874 0.4064)
			(stroke
				(width 0.1524)
				(type default)
			)
			(layer "B.SilkS")
		)
		(fp_line
			(start 0.67945 -0.305054)
			(end 0.12065 -0.305054)
			(stroke
				(width 0.1)
				(type default)
			)
			(layer "B.Fab")
		)
		(fp_line
			(start 0.12065 -0.305054)
			(end 0.12065 -0.2794)
			(stroke
				(width 0.1)
				(type default)
			)
			(layer "B.Fab")
		)
		(fp_line
			(start -0.12065 -0.3048)
			(end -0.67945 -0.3048)
			(stroke
				(width 0.1)
				(type default)
			)
			(layer "B.Fab")
		)
		(fp_line
			(start -0.67945 -0.3048)
			(end -0.67945 0.3048)
			(stroke
				(width 0.1)
				(type default)
			)
			(layer "B.Fab")
		)
		(fp_line
			(start 0.12065 -0.2794)
			(end -0.12065 -0.2794)
			(stroke
				(width 0.1)
				(type default)
			)
			(layer "B.Fab")
		)
		(fp_line
			(start -0.12065 -0.2794)
			(end -0.12065 -0.3048)
			(stroke
				(width 0.1)
				(type default)
			)
			(layer "B.Fab")
		)
		(fp_line
			(start 0.12065 0.2794)
			(end 0.12065 0.3048)
			(stroke
				(width 0.1)
				(type default)
			)
			(layer "B.Fab")
		)
		(fp_line
			(start -0.120396 0.2794)
			(end 0.12065 0.2794)
			(stroke
				(width 0.1)
				(type default)
			)
			(layer "B.Fab")
		)
		(fp_line
			(start 0.67945 0.3048)
			(end 0.67945 -0.305054)
			(stroke
				(width 0.1)
				(type default)
			)
			(layer "B.Fab")
		)
		(fp_line
			(start 0.12065 0.3048)
			(end 0.67945 0.3048)
			(stroke
				(width 0.1)
				(type default)
			)
			(layer "B.Fab")
		)
		(fp_line
			(start -0.120396 0.3048)
			(end -0.120396 0.2794)
			(stroke
				(width 0.1)
				(type default)
			)
			(layer "B.Fab")
		)
		(fp_line
			(start -0.67945 0.3048)
			(end -0.120396 0.3048)
			(stroke
				(width 0.1)
				(type default)
			)
			(layer "B.Fab")
		)
		(pad "1" smd circle
			(at 0.40005 0 270)
			(size 0 0)
			(layers "B.Cu" "B.Mask" "B.Paste")
			(net "PWRGD_CHA_CPU0_DIMM2")
		)
		(pad "2" smd circle
			(at -0.40005 0 270)
			(size 0 0)
			(layers "B.Cu" "B.Mask" "B.Paste")
			(net "PWRGD_FAIL_CPU0_AB")
		)
	)
	(footprint ""
		(layer "B.Cu")
		(at 170.78579 -319.006728 180)
		(property "Reference" "R79"
			(at 0 0 0)
			(layer "B.SilkS")
			(hide yes)
			(effects
				(font
					(size 1.27 1.27)
				)
				(justify mirror)
			)
		)
		(property "Value" ""
			(at 0 0 0)
			(layer "B.Fab")
			(effects
				(font
					(size 1.27 1.27)
				)
				(justify mirror)
			)
		)
		(duplicate_pad_numbers_are_jumpers no)
		(fp_line
			(start 0.7874 0.4064)
			(end 0.7874 -0.4064)
			(stroke
				(width 0.1524)
				(type default)
			)
			(layer "B.SilkS")
		)
		(fp_line
			(start 0.7874 -0.4064)
			(end -0.7874 -0.4064)
			(stroke
				(width 0.1524)
				(type default)
			)
			(layer "B.SilkS")
		)
		(fp_line
			(start -0.7874 0.4064)
			(end 0.7874 0.4064)
			(stroke
				(width 0.1524)
				(type default)
			)
			(layer "B.SilkS")
		)
		(fp_line
			(start -0.7874 -0.4064)
			(end -0.7874 0.4064)
			(stroke
				(width 0.1524)
				(type default)
			)
			(layer "B.SilkS")
		)
		(fp_line
			(start 0.67945 0.3048)
			(end 0.67945 -0.305054)
			(stroke
				(width 0.1)
				(type default)
			)
			(layer "B.Fab")
		)
		(fp_line
			(start 0.67945 -0.305054)
			(end 0.12065 -0.305054)
			(stroke
				(width 0.1)
				(type default)
			)
			(layer "B.Fab")
		)
		(fp_line
			(start 0.12065 0.3048)
			(end 0.67945 0.3048)
			(stroke
				(width 0.1)
				(type default)
			)
			(layer "B.Fab")
		)
		(fp_line
			(start 0.12065 0.2794)
			(end 0.12065 0.3048)
			(stroke
				(width 0.1)
				(type default)
			)
			(layer "B.Fab")
		)
		(fp_line
			(start 0.12065 -0.2794)
			(end -0.12065 -0.2794)
			(stroke
				(width 0.1)
				(type default)
			)
			(layer "B.Fab")
		)
		(fp_line
			(start 0.12065 -0.305054)
			(end 0.12065 -0.2794)
			(stroke
				(width 0.1)
				(type default)
			)
			(layer "B.Fab")
		)
		(fp_line
			(start -0.120396 0.3048)
			(end -0.120396 0.2794)
			(stroke
				(width 0.1)
				(type default)
			)
			(layer "B.Fab")
		)
		(fp_line
			(start -0.120396 0.2794)
			(end 0.12065 0.2794)
			(stroke
				(width 0.1)
				(type default)
			)
			(layer "B.Fab")
		)
		(fp_line
			(start -0.12065 -0.2794)
			(end -0.12065 -0.3048)
			(stroke
				(width 0.1)
				(type default)
			)
			(layer "B.Fab")
		)
		(fp_line
			(start -0.12065 -0.3048)
			(end -0.67945 -0.3048)
			(stroke
				(width 0.1)
				(type default)
			)
			(layer "B.Fab")
		)
		(fp_line
			(start -0.67945 0.3048)
			(end -0.120396 0.3048)
			(stroke
				(width 0.1)
				(type default)
			)
			(layer "B.Fab")
		)
		(fp_line
			(start -0.67945 -0.3048)
			(end -0.67945 0.3048)
			(stroke
				(width 0.1)
				(type default)
			)
			(layer "B.Fab")
		)
		(pad "1" smd circle
			(at 0.40005 0)
			(size 0 0)
			(layers "B.Cu" "B.Mask" "B.Paste")
			(net "PD_CHE_CPU1_DIMM1_SAA")
		)
		(pad "2" smd circle
			(at -0.40005 0)
			(size 0 0)
			(layers "B.Cu" "B.Mask" "B.Paste")
			(net "GND")
		)
	)
)
